(kicad_pcb
	(version 20241229)
	(generator "pcbnew")
	(generator_version "9.0")
	(general
		(thickness 1.711)
		(legacy_teardrops no)
	)
	(paper "A4")
	(title_block
		(title "Antmicro Baseboard for Jetson AGX Thor")
		(date "2026-02-18")
		(rev "1.1.0")
		(company "Antmicro Ltd")
		(comment 1 "www.antmicro.com")
		(comment 9 "footprints 133-137 of 1170")
	)
	(layers
		(0 "F.Cu" signal)
		(4 "In1.Cu" signal)
		(6 "In2.Cu" signal)
		(8 "In3.Cu" signal)
		(10 "In4.Cu" jumper)
		(12 "In5.Cu" signal)
		(14 "In6.Cu" signal)
		(16 "In7.Cu" signal)
		(18 "In8.Cu" signal)
		(2 "B.Cu" signal)
		(9 "F.Adhes" user "F.Adhesive")
		(11 "B.Adhes" user "B.Adhesive")
		(13 "F.Paste" user)
		(15 "B.Paste" user)
		(5 "F.SilkS" user "F.Silkscreen")
		(7 "B.SilkS" user "B.Silkscreen")
		(1 "F.Mask" user)
		(3 "B.Mask" user)
		(17 "Dwgs.User" user "User.Drawings")
		(19 "Cmts.User" user "User.Comments")
		(21 "Eco1.User" user "User.Eco1")
		(23 "Eco2.User" user "User.Eco2")
		(25 "Edge.Cuts" user)
		(27 "Margin" user)
		(31 "F.CrtYd" user "F.Courtyard")
		(29 "B.CrtYd" user "B.Courtyard")
		(35 "F.Fab" user)
		(33 "B.Fab" user)
	)
	(footprint "antmicro-footprints:R_0402_1005Metric"
		(layer "F.Cu")
		(at 183.25 139.95 180)
		(descr "Resistor SMD 0402")
		(tags "resistor SMD 0402")
		(property "Reference" "R326"
			(at -2.05 2.35 0)
			(layer "F.SilkS")
			(effects
				(font
					(size 0.7 0.7)
					(thickness 0.15)
				)
				(justify right top)
			)
		)
		(property "Value" "R_191k_0402"
			(at -1.011843 1.772047 0)
			(layer "F.Fab")
			(effects
				(font
					(size 0.7 0.7)
					(thickness 0.15)
				)
				(justify right top)
			)
		)
		(property "Datasheet" "https://www.bourns.com/docs/product-datasheets/cr.pdf"
			(at 0 0 0)
			(layer "F.Fab")
			(hide yes)
			(effects
				(font
					(size 1.27 1.27)
					(thickness 0.15)
				)
			)
		)
		(property "Description" "SMD Chip Resistor, 191 kohm, ± 1%, 100 mW, 0402 [1005 Metric], Thick Film, Precision"
			(at 0 0 0)
			(layer "F.Fab")
			(hide yes)
			(effects
				(font
					(size 1.27 1.27)
					(thickness 0.15)
				)
			)
		)
		(property "MPN" "CR0402-FX-1913GLF"
			(at 0 0 180)
			(unlocked yes)
			(layer "F.Fab")
			(hide yes)
			(effects
				(font
					(size 1 1)
					(thickness 0.15)
				)
			)
		)
		(property "Manufacturer" "Bourns"
			(at 0 0 180)
			(unlocked yes)
			(layer "F.Fab")
			(hide yes)
			(effects
				(font
					(size 1 1)
					(thickness 0.15)
				)
			)
		)
		(property "License" "Apache-2.0"
			(at 0 0 180)
			(unlocked yes)
			(layer "F.Fab")
			(hide yes)
			(effects
				(font
					(size 1 1)
					(thickness 0.15)
				)
			)
		)
		(property "Author" "Antmicro"
			(at 0 0 180)
			(unlocked yes)
			(layer "F.Fab")
			(hide yes)
			(effects
				(font
					(size 1 1)
					(thickness 0.15)
				)
			)
		)
		(property "Val" "191k"
			(at 0 0 180)
			(unlocked yes)
			(layer "F.Fab")
			(hide yes)
			(effects
				(font
					(size 1 1)
					(thickness 0.15)
				)
			)
		)
		(property "Tolerance" "1%"
			(at 0 0 180)
			(unlocked yes)
			(layer "F.Fab")
			(hide yes)
			(effects
				(font
					(size 1 1)
					(thickness 0.15)
				)
			)
		)
		(sheetname "/DCDC/")
		(sheetfile "dcdc.kicad_sch")
		(attr smd)
		(fp_rect
			(start -0.925 -0.47)
			(end 0.925 0.47)
			(stroke
				(width 0.05)
				(type default)
			)
			(fill no)
			(layer "F.CrtYd")
		)
		(fp_rect
			(start -0.5 -0.25)
			(end 0.5 0.25)
			(stroke
				(width 0.15)
				(type solid)
			)
			(fill no)
			(layer "F.Fab")
		)
		(fp_text user "${REFERENCE}"
			(at -0.95 3.168 0)
			(layer "F.Fab")
			(effects
				(font
					(size 0.7 0.7)
					(thickness 0.15)
				)
				(justify right top)
			)
		)
		(fp_text user "Author: Antmicro"
			(at -0.95 4.169 0)
			(layer "F.Fab")
			(effects
				(font
					(size 0.7 0.7)
					(thickness 0.15)
				)
				(justify right top)
			)
		)
		(fp_text user "License: Apache-2.0"
			(at -0.95 5.169 0)
			(layer "F.Fab")
			(effects
				(font
					(size 0.7 0.7)
					(thickness 0.15)
				)
				(justify right top)
			)
		)
		(pad "1" smd roundrect
			(at -0.48 0 180)
			(size 0.59 0.64)
			(layers "F.Cu" "F.Mask" "F.Paste")
			(roundrect_rratio 0.25)
			(net 1206 "/DCDC/12V_FB")
			(pintype "passive")
		)
		(pad "2" smd roundrect
			(at 0.48 0 180)
			(size 0.59 0.64)
			(layers "F.Cu" "F.Mask" "F.Paste")
			(roundrect_rratio 0.25)
			(net 880 "/DCDC/12V_OUT")
			(pintype "passive")
		)
	)
	(footprint "antmicro-footprints:TP_SMD_0.75mm"
		(layer "F.Cu")
		(at 201.15 73.45 -90)
		(property "Reference" "TP11"
			(at -3.45 0.15 270)
			(layer "F.SilkS")
			(effects
				(font
					(size 0.7 0.7)
					(thickness 0.15)
				)
				(justify right top)
			)
		)
		(property "Value" "TP_0.75mm_SMD"
			(at 0 1.2 90)
			(layer "F.Fab")
			(effects
				(font
					(size 0.7 0.7)
					(thickness 0.15)
				)
				(justify right top)
			)
		)
		(property "Description" "SMT test point"
			(at 0 0 90)
			(layer "F.Fab")
			(hide yes)
			(effects
				(font
					(size 1.27 1.27)
					(thickness 0.15)
				)
			)
		)
		(property "MPN" ""
			(at 0 0 270)
			(unlocked yes)
			(layer "F.Fab")
			(hide yes)
			(effects
				(font
					(size 1 1)
					(thickness 0.15)
				)
			)
		)
		(property "Manufacturer" ""
			(at 0 0 270)
			(unlocked yes)
			(layer "F.Fab")
			(hide yes)
			(effects
				(font
					(size 1 1)
					(thickness 0.15)
				)
			)
		)
		(property "Author" "Antmicro"
			(at 0 0 270)
			(unlocked yes)
			(layer "F.Fab")
			(hide yes)
			(effects
				(font
					(size 1 1)
					(thickness 0.15)
				)
			)
		)
		(property "License" "Apache-2.0"
			(at 0 0 270)
			(unlocked yes)
			(layer "F.Fab")
			(hide yes)
			(effects
				(font
					(size 1 1)
					(thickness 0.15)
				)
			)
		)
		(sheetname "/USB Debug, PD/")
		(sheetfile "usb_debug_pd.kicad_sch")
		(attr exclude_from_pos_files exclude_from_bom)
		(fp_circle
			(center 0 0)
			(end 0.475 0)
			(stroke
				(width 0.05)
				(type default)
			)
			(fill no)
			(layer "F.CrtYd")
		)
		(fp_text user "Author: Antmicro"
			(at -0.4 3.901 90)
			(layer "F.Fab")
			(effects
				(font
					(size 0.7 0.7)
					(thickness 0.15)
				)
				(justify right top)
			)
		)
		(fp_text user "License: Apache-2.0"
			(at -0.4 5.101 90)
			(layer "F.Fab")
			(effects
				(font
					(size 0.7 0.7)
					(thickness 0.15)
				)
				(justify right top)
			)
		)
		(fp_text user "${REFERENCE}"
			(at -0.4 2.7 90)
			(layer "F.Fab")
			(effects
				(font
					(size 0.7 0.7)
					(thickness 0.15)
				)
				(justify right top)
			)
		)
		(pad "1" smd circle
			(at 0 0 270)
			(size 0.75 0.75)
			(layers "F.Cu" "F.Mask")
			(net 1040 "/USB Debug, PD/PDC_I2C3_SDA")
			(pinfunction "1")
			(pintype "passive")
		)
	)
	(footprint "antmicro-footprints:SOD-523"
		(layer "F.Cu")
		(at 169.1 129.099 90)
		(property "Reference" "D9"
			(at -0.701 -0.75 90)
			(layer "F.SilkS")
			(effects
				(font
					(size 0.7 0.7)
					(thickness 0.15)
				)
				(justify left bottom)
			)
		)
		(property "Value" "PESD5Z5.0F"
			(at 0 1.499 90)
			(layer "F.Fab")
			(effects
				(font
					(size 0.7 0.7)
					(thickness 0.15)
				)
				(justify left bottom)
			)
		)
		(property "Datasheet" "https://assets.nexperia.com/documents/data-sheet/PESD5Z5_0.pdf"
			(at 0 0 90)
			(layer "F.Fab")
			(hide yes)
			(effects
				(font
					(size 1.27 1.27)
					(thickness 0.15)
				)
			)
		)
		(property "Description" "Unidirectional TVS, 30 kV,  SOD-523, 5 V, 89 pF"
			(at 0 0 90)
			(layer "F.Fab")
			(hide yes)
			(effects
				(font
					(size 1.27 1.27)
					(thickness 0.15)
				)
			)
		)
		(property "Manufacturer" "Nexperia"
			(at 0 0 90)
			(unlocked yes)
			(layer "F.Fab")
			(hide yes)
			(effects
				(font
					(size 1 1)
					(thickness 0.15)
				)
			)
		)
		(property "MPN" "PESD5Z5.0F"
			(at 0 0 90)
			(unlocked yes)
			(layer "F.Fab")
			(hide yes)
			(effects
				(font
					(size 1 1)
					(thickness 0.15)
				)
			)
		)
		(property "Author" "Antmicro"
			(at 0 0 90)
			(unlocked yes)
			(layer "F.Fab")
			(hide yes)
			(effects
				(font
					(size 1 1)
					(thickness 0.15)
				)
			)
		)
		(property "License" "Apache-2.0"
			(at 0 0 90)
			(unlocked yes)
			(layer "F.Fab")
			(hide yes)
			(effects
				(font
					(size 1 1)
					(thickness 0.15)
				)
			)
		)
		(sheetname "/DCDC/")
		(sheetfile "dcdc.kicad_sch")
		(attr smd)
		(fp_line
			(start -0.35 -0.5)
			(end -0.35 0.5)
			(stroke
				(width 0.15)
				(type solid)
			)
			(layer "F.SilkS")
		)
		(fp_rect
			(start -1 -0.6)
			(end 1 0.6)
			(stroke
				(width 0.05)
				(type solid)
			)
			(fill no)
			(layer "F.CrtYd")
		)
		(fp_line
			(start 0.65 -0.425)
			(end 0.65 0.423)
			(stroke
				(width 0.15)
				(type solid)
			)
			(layer "F.Fab")
		)
		(fp_line
			(start -0.652 -0.425)
			(end 0.65 -0.425)
			(stroke
				(width 0.15)
				(type solid)
			)
			(layer "F.Fab")
		)
		(fp_line
			(start -0.35 -0.4)
			(end -0.35 0.4)
			(stroke
				(width 0.15)
				(type solid)
			)
			(layer "F.Fab")
		)
		(fp_line
			(start -0.652 0.423)
			(end -0.652 -0.425)
			(stroke
				(width 0.15)
				(type solid)
			)
			(layer "F.Fab")
		)
		(fp_line
			(start -0.652 0.423)
			(end 0.65 0.423)
			(stroke
				(width 0.15)
				(type solid)
			)
			(layer "F.Fab")
		)
		(fp_text user "License: Apache-2.0"
			(at -1.276 5.9 90)
			(layer "F.Fab")
			(effects
				(font
					(size 0.7 0.7)
					(thickness 0.15)
				)
				(justify left bottom)
			)
		)
		(fp_text user "Author: Antmicro"
			(at -1.276 4.7 90)
			(layer "F.Fab")
			(effects
				(font
					(size 0.7 0.7)
					(thickness 0.15)
				)
				(justify left bottom)
			)
		)
		(fp_text user "${REFERENCE}"
			(at -1.276 3.499 90)
			(layer "F.Fab")
			(effects
				(font
					(size 0.7 0.7)
					(thickness 0.15)
				)
				(justify left bottom)
			)
		)
		(pad "1" smd roundrect
			(at -0.701 0 90)
			(size 0.5 0.6)
			(layers "F.Cu" "F.Mask" "F.Paste")
			(roundrect_rratio 0.25)
			(net 2 "+3V3")
			(pinfunction "C")
			(pintype "passive")
		)
		(pad "2" smd roundrect
			(at 0.699 0 90)
			(size 0.5 0.6)
			(layers "F.Cu" "F.Mask" "F.Paste")
			(roundrect_rratio 0.25)
			(net 1 "GND")
			(pinfunction "A")
			(pintype "passive")
		)
	)
	(footprint "antmicro-footprints:C_0805_2012Metric"
		(layer "F.Cu")
		(at 126.17 55.68)
		(descr "Capacitor SMD 0805")
		(tags "capacitor SMD 0805")
		(property "Reference" "C372"
			(at -8.76 9.73 0)
			(layer "F.SilkS")
			(effects
				(font
					(size 0.7 0.7)
					(thickness 0.15)
				)
				(justify left bottom)
			)
		)
		(property "Value" "C_22u_25V_0805"
			(at -2.055717 1.963153 0)
			(layer "F.Fab")
			(effects
				(font
					(size 0.7 0.7)
					(thickness 0.15)
				)
				(justify left bottom)
			)
		)
		(property "Datasheet" "https://product.samsungsem.com/mlcc/CL21A226MAYNNN.do"
			(at 0 0 0)
			(layer "F.Fab")
			(hide yes)
			(effects
				(font
					(size 1.27 1.27)
					(thickness 0.15)
				)
			)
		)
		(property "Description" "SMT Multilayer Ceramic Capacitor, 22uF, +/-20%, 25V, X5R, 0805 [2012 Metric]"
			(at 0 0 0)
			(layer "F.Fab")
			(hide yes)
			(effects
				(font
					(size 1.27 1.27)
					(thickness 0.15)
				)
			)
		)
		(property "MPN" "CL21A226MAYNNNE"
			(at 0 0 0)
			(unlocked yes)
			(layer "F.Fab")
			(hide yes)
			(effects
				(font
					(size 1 1)
					(thickness 0.15)
				)
			)
		)
		(property "Manufacturer" "Samsung Electro-Mechanics"
			(at 0 0 0)
			(unlocked yes)
			(layer "F.Fab")
			(hide yes)
			(effects
				(font
					(size 1 1)
					(thickness 0.15)
				)
			)
		)
		(property "License" "Apache-2.0"
			(at 0 0 0)
			(unlocked yes)
			(layer "F.Fab")
			(hide yes)
			(effects
				(font
					(size 1 1)
					(thickness 0.15)
				)
			)
		)
		(property "Author" "Antmicro"
			(at 0 0 0)
			(unlocked yes)
			(layer "F.Fab")
			(hide yes)
			(effects
				(font
					(size 1 1)
					(thickness 0.15)
				)
			)
		)
		(property "Val" "22u"
			(at 0 0 0)
			(unlocked yes)
			(layer "F.Fab")
			(hide yes)
			(effects
				(font
					(size 1 1)
					(thickness 0.15)
				)
			)
		)
		(property "Voltage" "25V"
			(at 0 0 0)
			(unlocked yes)
			(layer "F.Fab")
			(hide yes)
			(effects
				(font
					(size 1 1)
					(thickness 0.15)
				)
			)
		)
		(property "Dielectric" "X5R"
			(at 0 0 0)
			(unlocked yes)
			(layer "F.Fab")
			(hide yes)
			(effects
				(font
					(size 1 1)
					(thickness 0.15)
				)
			)
		)
		(property "Public" "False"
			(at 0 0 0)
			(unlocked yes)
			(layer "F.Fab")
			(hide yes)
			(effects
				(font
					(size 1 1)
					(thickness 0.15)
				)
			)
		)
		(sheetname "/DCDC/")
		(sheetfile "dcdc.kicad_sch")
		(attr smd)
		(fp_line
			(start -0.3 -0.7)
			(end 0.3 -0.7)
			(stroke
				(width 0.15)
				(type solid)
			)
			(layer "F.SilkS")
		)
		(fp_line
			(start -0.3 0.7)
			(end 0.3 0.7)
			(stroke
				(width 0.15)
				(type solid)
			)
			(layer "F.SilkS")
		)
		(fp_poly
			(pts
				(xy 1.95 -0.9) (xy 1.95 0.9) (xy -1.95 0.9) (xy -1.95 -0.9)
			)
			(stroke
				(width 0.05)
				(type default)
			)
			(fill no)
			(layer "F.CrtYd")
		)
		(fp_poly
			(pts
				(xy -0.95 -0.675001) (xy -0.95 0.675001) (xy 0.95 0.675001) (xy 0.95 -0.675001)
			)
			(stroke
				(width 0.15)
				(type solid)
			)
			(fill no)
			(layer "F.Fab")
		)
		(fp_text user "${REFERENCE}"
			(at -1.899999 3.947 0)
			(layer "F.Fab")
			(effects
				(font
					(size 0.7 0.7)
					(thickness 0.15)
				)
				(justify left bottom)
			)
		)
		(fp_text user "License: Apache-2.0"
			(at -1.9 4.947 0)
			(layer "F.Fab")
			(effects
				(font
					(size 0.7 0.7)
					(thickness 0.15)
				)
				(justify left bottom)
			)
		)
		(fp_text user "Author: Antmicro"
			(at -1.9 5.947 0)
			(layer "F.Fab")
			(effects
				(font
					(size 0.7 0.7)
					(thickness 0.15)
				)
				(justify left bottom)
			)
		)
		(pad "1" smd roundrect
			(at -1.099999 0)
			(size 1.2 1.3)
			(layers "F.Cu" "F.Mask" "F.Paste")
			(roundrect_rratio 0.25)
			(net 1 "GND")
			(pintype "passive")
		)
		(pad "2" smd roundrect
			(at 1.099999 0)
			(size 1.2 1.3)
			(layers "F.Cu" "F.Mask" "F.Paste")
			(roundrect_rratio 0.25)
			(net 13 "VCC")
			(pintype "passive")
		)
	)
	(footprint "antmicro-footprints:C_0402_1005Metric"
		(layer "F.Cu")
		(at 214.554132 84.282 -90)
		(descr "Capacitor SMD 0402")
		(tags "capacitor SMD 0402")
		(property "Reference" "C127"
			(at -3.682 0.324132 90)
			(layer "F.SilkS")
			(effects
				(font
					(size 0.7 0.7)
					(thickness 0.15)
				)
				(justify right top)
			)
		)
		(property "Value" "C_100n_0402"
			(at -1.022927 2.155213 90)
			(layer "F.Fab")
			(effects
				(font
					(size 0.7 0.7)
					(thickness 0.15)
				)
				(justify right top)
			)
		)
		(property "Datasheet" "https://www.murata.com/products/productdetail?partno=GRM155R61H104KE14%23"
			(at 0 0 90)
			(layer "F.Fab")
			(hide yes)
			(effects
				(font
					(size 1.27 1.27)
					(thickness 0.15)
				)
			)
		)
		(property "Description" "SMD Multilayer Ceramic Capacitor, 0.1 µF, 50 V, 0402 [1005 Metric], ± 10%, X5R, GRM Series"
			(at 0 0 90)
			(layer "F.Fab")
			(hide yes)
			(effects
				(font
					(size 1.27 1.27)
					(thickness 0.15)
				)
			)
		)
		(property "Manufacturer" "Murata"
			(at 0 0 270)
			(unlocked yes)
			(layer "F.Fab")
			(hide yes)
			(effects
				(font
					(size 1 1)
					(thickness 0.15)
				)
			)
		)
		(property "MPN" "GRM155R61H104KE14D"
			(at 0 0 270)
			(unlocked yes)
			(layer "F.Fab")
			(hide yes)
			(effects
				(font
					(size 1 1)
					(thickness 0.15)
				)
			)
		)
		(property "Val" "100n"
			(at 0 0 270)
			(unlocked yes)
			(layer "F.Fab")
			(hide yes)
			(effects
				(font
					(size 1 1)
					(thickness 0.15)
				)
			)
		)
		(property "License" "Apache-2.0"
			(at 0 0 270)
			(unlocked yes)
			(layer "F.Fab")
			(hide yes)
			(effects
				(font
					(size 1 1)
					(thickness 0.15)
				)
			)
		)
		(property "Author" "Antmicro"
			(at 0 0 270)
			(unlocked yes)
			(layer "F.Fab")
			(hide yes)
			(effects
				(font
					(size 1 1)
					(thickness 0.15)
				)
			)
		)
		(property "Voltage" "50V"
			(at 0 0 270)
			(unlocked yes)
			(layer "F.Fab")
			(hide yes)
			(effects
				(font
					(size 1 1)
					(thickness 0.15)
				)
			)
		)
		(property "Dielectric" "X5R"
			(at 0 0 270)
			(unlocked yes)
			(layer "F.Fab")
			(hide yes)
			(effects
				(font
					(size 1 1)
					(thickness 0.15)
				)
			)
		)
		(sheetname "/USB DP Alt mode/")
		(sheetfile "usb_dp.kicad_sch")
		(attr smd)
		(fp_rect
			(start -0.925 -0.47)
			(end 0.925 0.47)
			(stroke
				(width 0.05)
				(type default)
			)
			(fill no)
			(layer "F.CrtYd")
		)
		(fp_line
			(start -0.494 0.248)
			(end -0.494 -0.25)
			(stroke
				(width 0.15)
				(type solid)
			)
			(layer "F.Fab")
		)
		(fp_line
			(start 0.504 0.248)
			(end -0.494 0.248)
			(stroke
				(width 0.15)
				(type solid)
			)
			(layer "F.Fab")
		)
		(fp_line
			(start -0.494 -0.25)
			(end 0.504 -0.25)
			(stroke
				(width 0.15)
				(type solid)
			)
			(layer "F.Fab")
		)
		(fp_line
			(start 0.504 -0.25)
			(end 0.504 0.248)
			(stroke
				(width 0.15)
				(type solid)
			)
			(layer "F.Fab")
		)
		(fp_text user "License: Apache-2.0"
			(at -0.939 5.799 90)
			(layer "F.Fab")
			(effects
				(font
					(size 0.7 0.7)
					(thickness 0.15)
				)
				(justify right top)
			)
		)
		(fp_text user "${REFERENCE}"
			(at -0.939 4.599 90)
			(layer "F.Fab")
			(effects
				(font
					(size 0.7 0.7)
					(thickness 0.15)
				)
				(justify right top)
			)
		)
		(fp_text user "Author: Antmicro"
			(at -0.939 3.399 90)
			(layer "F.Fab")
			(effects
				(font
					(size 0.7 0.7)
					(thickness 0.15)
				)
				(justify right top)
			)
		)
		(pad "1" smd roundrect
			(at -0.48 0 270)
			(size 0.59 0.64)
			(layers "F.Cu" "F.Mask" "F.Paste")
			(roundrect_rratio 0.25)
			(net 299 "/SoM_IO2/USBSS1.RX+")
			(pintype "passive")
		)
		(pad "2" smd roundrect
			(at 0.48 0 270)
			(size 0.59 0.64)
			(layers "F.Cu" "F.Mask" "F.Paste")
			(roundrect_rratio 0.25)
			(net 302 "/USB DP Alt mode/USBSS1_RX_C_P")
			(pintype "passive")
		)
	)
)
